(kicad_pcb
	(version 20241229)
	(generator "pcbnew")
	(generator_version "9.0")
	(general
		(thickness 1.63)
		(legacy_teardrops no)
	)
	(paper "A4")
	(title_block
		(title "CM4 Baseboard")
		(date "2026-01-05")
		(rev "1.1.1")
		(company "Antmicro Ltd")
		(comment 1 "www.antmicro.com")
		(comment 9 "footprints 16-19 of 506")
	)
	(layers
		(0 "F.Cu" signal)
		(4 "In1.Cu" power)
		(6 "In2.Cu" power)
		(8 "In3.Cu" signal)
		(10 "In4.Cu" signal)
		(2 "B.Cu" signal)
		(9 "F.Adhes" user "F.Adhesive")
		(11 "B.Adhes" user "B.Adhesive")
		(13 "F.Paste" user)
		(15 "B.Paste" user)
		(5 "F.SilkS" user "F.Silkscreen")
		(7 "B.SilkS" user "B.Silkscreen")
		(1 "F.Mask" user)
		(3 "B.Mask" user)
		(17 "Dwgs.User" user "User.Drawings")
		(19 "Cmts.User" user "User.Comments")
		(21 "Eco1.User" user "User.Eco1")
		(23 "Eco2.User" user "User.Eco2")
		(25 "Edge.Cuts" user)
		(27 "Margin" user)
		(31 "F.CrtYd" user "F.Courtyard")
		(29 "B.CrtYd" user "B.Courtyard")
		(35 "F.Fab" user)
		(33 "B.Fab" user)
	)
	(footprint "antmicro-footprints:SOT-523"
		(layer "F.Cu")
		(at 54.717962 135.3165 -90)
		(property "Reference" "Q401"
			(at 1.8335 -0.832038 180)
			(layer "F.SilkS")
			(effects
				(font
					(size 0.7 0.7)
					(thickness 0.15)
				)
				(justify right bottom)
			)
		)
		(property "Value" "PJE138K"
			(at 0.1 1.824 90)
			(layer "F.Fab")
			(effects
				(font
					(size 0.7 0.7)
					(thickness 0.15)
				)
				(justify right bottom)
			)
		)
		(property "Datasheet" "https://www.mouser.com/datasheet/2/1057/PJE138K-1876698.pdf"
			(at 0 0 270)
			(layer "F.Fab")
			(hide yes)
			(effects
				(font
					(size 1.27 1.27)
					(thickness 0.15)
				)
			)
		)
		(property "MPN" "PJE138K_R1_00001"
			(at 0 0 270)
			(unlocked yes)
			(layer "F.Fab")
			(hide yes)
			(effects
				(font
					(size 1 1)
					(thickness 0.15)
				)
			)
		)
		(property "Manufacturer" "PANJIT"
			(at 0 0 270)
			(unlocked yes)
			(layer "F.Fab")
			(hide yes)
			(effects
				(font
					(size 1 1)
					(thickness 0.15)
				)
			)
		)
		(property "Author" "Antmicro"
			(at 0 0 270)
			(unlocked yes)
			(layer "F.Fab")
			(hide yes)
			(effects
				(font
					(size 1 1)
					(thickness 0.15)
				)
			)
		)
		(property "License" "Apache-2.0"
			(at 0 0 270)
			(unlocked yes)
			(layer "F.Fab")
			(hide yes)
			(effects
				(font
					(size 1 1)
					(thickness 0.15)
				)
			)
		)
		(sheetname "/Ethernet/")
		(sheetfile "ethernet.kicad_sch")
		(attr smd)
		(fp_line
			(start -0.927 -0.051)
			(end -0.927 -0.351)
			(stroke
				(width 0.15)
				(type solid)
			)
			(layer "F.SilkS")
		)
		(fp_line
			(start -0.927 -0.351)
			(end -0.725 -0.551)
			(stroke
				(width 0.15)
				(type solid)
			)
			(layer "F.SilkS")
		)
		(fp_line
			(start -0.725 -0.551)
			(end -0.277 -0.551)
			(stroke
				(width 0.15)
				(type solid)
			)
			(layer "F.SilkS")
		)
		(fp_line
			(start -0.277 -0.551)
			(end -0.277 -0.75)
			(stroke
				(width 0.15)
				(type solid)
			)
			(layer "F.SilkS")
		)
		(fp_circle
			(center -0.9652 0.9652)
			(end -0.9152 0.9652)
			(stroke
				(width 0.15)
				(type solid)
			)
			(fill yes)
			(layer "F.SilkS")
		)
		(fp_line
			(start -1.12 1.15)
			(end 1.1 1.15)
			(stroke
				(width 0.05)
				(type solid)
			)
			(layer "F.CrtYd")
		)
		(fp_line
			(start -1.12 -1.16)
			(end -1.12 1.15)
			(stroke
				(width 0.05)
				(type solid)
			)
			(layer "F.CrtYd")
		)
		(fp_line
			(start -1.12 -1.16)
			(end 1.1 -1.16)
			(stroke
				(width 0.05)
				(type solid)
			)
			(layer "F.CrtYd")
		)
		(fp_line
			(start 1.1 -1.16)
			(end 1.1 1.15)
			(stroke
				(width 0.05)
				(type solid)
			)
			(layer "F.CrtYd")
		)
		(fp_line
			(start 0.8 0.424)
			(end -0.802 0.424)
			(stroke
				(width 0.15)
				(type solid)
			)
			(layer "F.Fab")
		)
		(fp_line
			(start -0.802 -0.276)
			(end -0.802 0.424)
			(stroke
				(width 0.15)
				(type solid)
			)
			(layer "F.Fab")
		)
		(fp_line
			(start -0.652 -0.425)
			(end -0.802 -0.276)
			(stroke
				(width 0.15)
				(type solid)
			)
			(layer "F.Fab")
		)
		(fp_line
			(start 0.8 -0.425)
			(end 0.8 0.424)
			(stroke
				(width 0.15)
				(type solid)
			)
			(layer "F.Fab")
		)
		(fp_line
			(start 0.8 -0.425)
			(end -0.652 -0.425)
			(stroke
				(width 0.15)
				(type solid)
			)
			(layer "F.Fab")
		)
		(fp_circle
			(center -0.9652 0.9652)
			(end -0.9144 0.9652)
			(stroke
				(width 0.15)
				(type solid)
			)
			(fill no)
			(layer "F.Fab")
		)
		(fp_text user "${REFERENCE}"
			(at -1.12 3.824 270)
			(layer "F.Fab")
			(effects
				(font
					(size 0.7 0.7)
					(thickness 0.15)
				)
				(justify left bottom)
			)
		)
		(fp_text user "Author: Antmicro"
			(at -1.12 6.224 270)
			(layer "F.Fab")
			(effects
				(font
					(size 0.7 0.7)
					(thickness 0.15)
				)
				(justify left bottom)
			)
		)
		(fp_text user "License: Apache-2.0"
			(at -1.12 5.024 270)
			(layer "F.Fab")
			(effects
				(font
					(size 0.7 0.7)
					(thickness 0.15)
				)
				(justify left bottom)
			)
		)
		(pad "1" smd rect
			(at -0.5 0.65 270)
			(size 0.4 0.51)
			(layers "F.Cu" "F.Mask" "F.Paste")
			(net 339 "/Ethernet/POE_ACTIVE")
			(pinfunction "G")
			(pintype "input")
		)
		(pad "2" smd rect
			(at 0.498 0.65 270)
			(size 0.4 0.51)
			(layers "F.Cu" "F.Mask" "F.Paste")
			(net 1 "GNDD")
			(pinfunction "S")
			(pintype "passive")
		)
		(pad "3" smd rect
			(at 0 -0.652 270)
			(size 0.4 0.51)
			(layers "F.Cu" "F.Mask" "F.Paste")
			(net 126 "/Ethernet/ULS-12_CTRL")
			(pinfunction "D")
			(pintype "passive")
		)
	)
	(footprint "antmicro-footprints:Conn_JST_SH_1x2_SM02B-SRSS-TB-LF-SN"
		(layer "F.Cu")
		(at 55.117962 176.8255 -90)
		(property "Reference" "J804"
			(at -2.2255 0.167962 0)
			(layer "F.SilkS")
			(effects
				(font
					(size 0.7 0.7)
					(thickness 0.15)
				)
				(justify left bottom)
			)
		)
		(property "Value" "JST_SH_1x2_SM02B-SRSS-TB-LF-SN"
			(at -2.7 6.195 90)
			(layer "F.Fab")
			(effects
				(font
					(size 0.7 0.7)
					(thickness 0.15)
				)
				(justify right bottom)
			)
		)
		(property "Datasheet" "https://www.jst-mfg.com/product/pdf/eng/eSH.pdf"
			(at 0 0 270)
			(layer "F.Fab")
			(hide yes)
			(effects
				(font
					(size 1.27 1.27)
					(thickness 0.15)
				)
			)
		)
		(property "MPN" "SM02B-SRSS-TB(LF)(SN)"
			(at 0 0 270)
			(unlocked yes)
			(layer "F.Fab")
			(hide yes)
			(effects
				(font
					(size 1 1)
					(thickness 0.15)
				)
			)
		)
		(property "Manufacturer" "JST Automotive Connectors"
			(at 0 0 270)
			(unlocked yes)
			(layer "F.Fab")
			(hide yes)
			(effects
				(font
					(size 1 1)
					(thickness 0.15)
				)
			)
		)
		(property "Author" "Antmicro"
			(at 0 0 270)
			(unlocked yes)
			(layer "F.Fab")
			(hide yes)
			(effects
				(font
					(size 1 1)
					(thickness 0.15)
				)
			)
		)
		(property "License" "Apache-2.0"
			(at 0 0 270)
			(unlocked yes)
			(layer "F.Fab")
			(hide yes)
			(effects
				(font
					(size 1 1)
					(thickness 0.15)
				)
			)
		)
		(sheetname "/Peripherals/")
		(sheetfile "peripherals.kicad_sch")
		(attr smd)
		(fp_line
			(start -0.9 2.6)
			(end 0.9 2.6)
			(stroke
				(width 0.15)
				(type solid)
			)
			(layer "F.SilkS")
		)
		(fp_line
			(start -2 -1.651)
			(end -2 0.7)
			(stroke
				(width 0.15)
				(type solid)
			)
			(layer "F.SilkS")
		)
		(fp_line
			(start -2 -1.651)
			(end -1 -1.651)
			(stroke
				(width 0.15)
				(type solid)
			)
			(layer "F.SilkS")
		)
		(fp_line
			(start 2 -1.651)
			(end 2 0.7)
			(stroke
				(width 0.15)
				(type solid)
			)
			(layer "F.SilkS")
		)
		(fp_line
			(start 2 -1.651)
			(end 1 -1.651)
			(stroke
				(width 0.15)
				(type solid)
			)
			(layer "F.SilkS")
		)
		(fp_circle
			(center -1.1 -2.4)
			(end -1.05 -2.4)
			(stroke
				(width 0.15)
				(type solid)
			)
			(fill yes)
			(layer "F.SilkS")
		)
		(fp_rect
			(start -2.55 -2.92)
			(end 2.55 2.95)
			(stroke
				(width 0.05)
				(type solid)
			)
			(fill no)
			(layer "F.CrtYd")
		)
		(fp_rect
			(start -2 -2.475)
			(end 2 2.475)
			(stroke
				(width 0.15)
				(type solid)
			)
			(fill no)
			(layer "F.Fab")
		)
		(fp_text user "Author: Antmicro"
			(at -2.7 10.595 270)
			(layer "F.Fab")
			(effects
				(font
					(size 0.7 0.7)
					(thickness 0.15)
				)
				(justify left bottom)
			)
		)
		(fp_text user "${REFERENCE}"
			(at -2.7 8.195 270)
			(layer "F.Fab")
			(effects
				(font
					(size 0.7 0.7)
					(thickness 0.15)
				)
				(justify left bottom)
			)
		)
		(fp_text user "License: Apache-2.0"
			(at -2.7 9.395 270)
			(layer "F.Fab")
			(effects
				(font
					(size 0.7 0.7)
					(thickness 0.15)
				)
				(justify left bottom)
			)
		)
		(pad "1" smd roundrect
			(at -0.5 -1.975)
			(size 1.55 0.6)
			(layers "F.Cu" "F.Mask" "F.Paste")
			(roundrect_rratio 0.25)
			(net 319 "Net-(J804-Pad1)")
			(pintype "passive")
		)
		(pad "2" smd roundrect
			(at 0.5 -1.975)
			(size 1.55 0.6)
			(layers "F.Cu" "F.Mask" "F.Paste")
			(roundrect_rratio 0.25)
			(net 320 "Net-(J804-Pad2)")
			(pintype "passive")
		)
		(pad "MP" smd roundrect
			(at -1.8 1.9)
			(size 1.8 1.2)
			(layers "F.Cu" "F.Mask" "F.Paste")
			(roundrect_rratio 0.25)
			(net 3 "GND")
			(pintype "passive")
		)
		(pad "MP" smd roundrect
			(at 1.8 1.9)
			(size 1.8 1.2)
			(layers "F.Cu" "F.Mask" "F.Paste")
			(roundrect_rratio 0.25)
			(net 3 "GND")
			(pintype "passive")
		)
	)
	(footprint "antmicro-footprints:LED_0603_1608Metric_G"
		(layer "F.Cu")
		(at 75.767962 150.2915 180)
		(descr "LED SMD 0603 Green")
		(tags "LED SMD 0603 Green")
		(property "Reference" "D205"
			(at -1.15 6.125 0)
			(layer "F.SilkS")
			(effects
				(font
					(size 0.7 0.7)
					(thickness 0.15)
				)
				(justify right bottom)
			)
		)
		(property "Value" "LED_G_0603_KP-1608CGCK"
			(at -0.001 1.599 0)
			(layer "F.Fab")
			(effects
				(font
					(size 0.7 0.7)
					(thickness 0.15)
				)
				(justify right bottom)
			)
		)
		(property "Datasheet" "http://www.kingbright.com/attachments/file/psearch//000/00/00/KP-1608CGCK(Ver.23B).pdf"
			(at 0 0 180)
			(layer "F.Fab")
			(hide yes)
			(effects
				(font
					(size 1.27 1.27)
					(thickness 0.15)
				)
			)
		)
		(property "MPN" "KP-1608CGCK"
			(at 0 0 180)
			(unlocked yes)
			(layer "F.Fab")
			(hide yes)
			(effects
				(font
					(size 1 1)
					(thickness 0.15)
				)
			)
		)
		(property "Manufacturer" "Kingbright"
			(at 0 0 180)
			(unlocked yes)
			(layer "F.Fab")
			(hide yes)
			(effects
				(font
					(size 1 1)
					(thickness 0.15)
				)
			)
		)
		(property "Color" "Green"
			(at 0 0 180)
			(unlocked yes)
			(layer "F.Fab")
			(hide yes)
			(effects
				(font
					(size 1 1)
					(thickness 0.15)
				)
			)
		)
		(property "Author" "Antmicro"
			(at 0 0 180)
			(unlocked yes)
			(layer "F.Fab")
			(hide yes)
			(effects
				(font
					(size 1 1)
					(thickness 0.15)
				)
			)
		)
		(property "License" "Apache-2.0"
			(at 0 0 180)
			(unlocked yes)
			(layer "F.Fab")
			(hide yes)
			(effects
				(font
					(size 1 1)
					(thickness 0.15)
				)
			)
		)
		(sheetname "/Compute module/")
		(sheetfile "compute-module.kicad_sch")
		(attr smd)
		(fp_line
			(start 0.22 0.35)
			(end -0.22 0.35)
			(stroke
				(width 0.15)
				(type solid)
			)
			(layer "F.SilkS")
		)
		(fp_line
			(start 0.22 -0.35)
			(end -0.22 -0.35)
			(stroke
				(width 0.15)
				(type solid)
			)
			(layer "F.SilkS")
		)
		(fp_line
			(start 0.105328 0.201008)
			(end 0.105328 -0.198992)
			(stroke
				(width 0.1)
				(type solid)
			)
			(layer "F.SilkS")
		)
		(fp_line
			(start 0.105328 0.201008)
			(end -0.094672 0.001008)
			(stroke
				(width 0.1)
				(type solid)
			)
			(layer "F.SilkS")
		)
		(fp_line
			(start 0.105328 0.001008)
			(end 0.24 0.001)
			(stroke
				(width 0.1)
				(type solid)
			)
			(layer "F.SilkS")
		)
		(fp_line
			(start -0.094672 0.201008)
			(end -0.094672 -0.198992)
			(stroke
				(width 0.1)
				(type solid)
			)
			(layer "F.SilkS")
		)
		(fp_line
			(start -0.094672 0.001008)
			(end 0.105328 -0.198992)
			(stroke
				(width 0.1)
				(type solid)
			)
			(layer "F.SilkS")
		)
		(fp_line
			(start -0.094672 0.001008)
			(end -0.24 0.001008)
			(stroke
				(width 0.1)
				(type solid)
			)
			(layer "F.SilkS")
		)
		(fp_line
			(start -1.18 -0.319)
			(end -1.18 0.321)
			(stroke
				(width 0.15)
				(type solid)
			)
			(layer "F.SilkS")
		)
		(fp_rect
			(start 1.25 0.65)
			(end -1.25 -0.65)
			(stroke
				(width 0.05)
				(type solid)
			)
			(fill no)
			(layer "F.CrtYd")
		)
		(fp_line
			(start 0.599 0)
			(end 0.201 0)
			(stroke
				(width 0.15)
				(type solid)
			)
			(layer "F.Fab")
		)
		(fp_line
			(start 0.201 0.2)
			(end 0.201 0)
			(stroke
				(width 0.15)
				(type solid)
			)
			(layer "F.Fab")
		)
		(fp_line
			(start 0.201 0)
			(end 0.201 -0.202)
			(stroke
				(width 0.15)
				(type solid)
			)
			(layer "F.Fab")
		)
		(fp_line
			(start 0.201 -0.202)
			(end -0.101 0)
			(stroke
				(width 0.15)
				(type solid)
			)
			(layer "F.Fab")
		)
		(fp_line
			(start -0.101 0)
			(end 0.201 0.2)
			(stroke
				(width 0.15)
				(type solid)
			)
			(layer "F.Fab")
		)
		(fp_line
			(start -0.199 0.2)
			(end -0.199 0.1)
			(stroke
				(width 0.15)
				(type solid)
			)
			(layer "F.Fab")
		)
		(fp_line
			(start -0.199 0)
			(end -0.597 0)
			(stroke
				(width 0.15)
				(type solid)
			)
			(layer "F.Fab")
		)
		(fp_line
			(start -0.199 -0.202)
			(end -0.199 0.1)
			(stroke
				(width 0.15)
				(type solid)
			)
			(layer "F.Fab")
		)
		(fp_rect
			(start 0.848 0.4)
			(end -0.85 -0.402)
			(stroke
				(width 0.15)
				(type solid)
			)
			(fill no)
			(layer "F.Fab")
		)
		(fp_text user "${REFERENCE}"
			(at -1.4224 5.999 180)
			(layer "F.Fab")
			(effects
				(font
					(size 0.7 0.7)
					(thickness 0.15)
				)
				(justify left bottom)
			)
		)
		(fp_text user "Author: Antmicro"
			(at -1.4224 4.799 180)
			(layer "F.Fab")
			(effects
				(font
					(size 0.7 0.7)
					(thickness 0.15)
				)
				(justify left bottom)
			)
		)
		(fp_text user "License: Apache-2.0"
			(at -1.4224 3.599 180)
			(layer "F.Fab")
			(effects
				(font
					(size 0.7 0.7)
					(thickness 0.15)
				)
				(justify left bottom)
			)
		)
		(pad "1" smd roundrect
			(at -0.7 0)
			(size 0.8 1)
			(layers "F.Cu" "F.Mask" "F.Paste")
			(roundrect_rratio 0.2)
			(net 465 "Net-(D205-C)")
			(pinfunction "C")
			(pintype "passive")
		)
		(pad "2" smd roundrect
			(at 0.7 0)
			(size 0.8 1)
			(layers "F.Cu" "F.Mask" "F.Paste")
			(roundrect_rratio 0.2)
			(net 10 "+5V")
			(pinfunction "A")
			(pintype "passive")
		)
	)
	(footprint "antmicro-footprints:TP_SMD_0.75mm"
		(layer "F.Cu")
		(at 95.517962 139.757236)
		(property "Reference" "TP907"
			(at 0.45 0.519264 0)
			(layer "F.SilkS")
			(effects
				(font
					(size 0.7 0.7)
					(thickness 0.15)
				)
				(justify left bottom)
			)
		)
		(property "Value" "TP_0.75mm_SMD"
			(at 0 1.2 0)
			(layer "F.Fab")
			(effects
				(font
					(size 0.7 0.7)
					(thickness 0.15)
				)
				(justify left bottom)
			)
		)
		(property "MPN" ""
			(at 0 0 0)
			(unlocked yes)
			(layer "F.Fab")
			(hide yes)
			(effects
				(font
					(size 1 1)
					(thickness 0.15)
				)
			)
		)
		(property "Manufacturer" ""
			(at 0 0 0)
			(unlocked yes)
			(layer "F.Fab")
			(hide yes)
			(effects
				(font
					(size 1 1)
					(thickness 0.15)
				)
			)
		)
		(property "Author" "Antmicro"
			(at 0 0 0)
			(unlocked yes)
			(layer "F.Fab")
			(hide yes)
			(effects
				(font
					(size 1 1)
					(thickness 0.15)
				)
			)
		)
		(property "License" "Apache-2.0"
			(at 0 0 0)
			(unlocked yes)
			(layer "F.Fab")
			(hide yes)
			(effects
				(font
					(size 1 1)
					(thickness 0.15)
				)
			)
		)
		(sheetname "/USB/")
		(sheetfile "usb.kicad_sch")
		(attr exclude_from_pos_files exclude_from_bom)
		(fp_circle
			(center 0 0)
			(end 0.475 0)
			(stroke
				(width 0.05)
				(type default)
			)
			(fill no)
			(layer "F.CrtYd")
		)
		(fp_text user "Author: Antmicro"
			(at -0.4 3.901 0)
			(layer "F.Fab")
			(effects
				(font
					(size 0.7 0.7)
					(thickness 0.15)
				)
				(justify left bottom)
			)
		)
		(fp_text user "${REFERENCE}"
			(at -0.4 2.7 0)
			(layer "F.Fab")
			(effects
				(font
					(size 0.7 0.7)
					(thickness 0.15)
				)
				(justify left bottom)
			)
		)
		(fp_text user "License: Apache-2.0"
			(at -0.4 5.101 0)
			(layer "F.Fab")
			(effects
				(font
					(size 0.7 0.7)
					(thickness 0.15)
				)
				(justify left bottom)
			)
		)
		(pad "1" smd circle
			(at 0 0)
			(size 0.75 0.75)
			(layers "F.Cu" "F.Mask")
			(net 384 "Net-(U905-GPIO6)")
			(pinfunction "1")
			(pintype "passive")
		)
	)
)
